(kicad_pcb
	(version 20260206)
	(generator "pcbnew")
	(generator_version "10.0")
	(general
		(thickness 1.6)
		(legacy_teardrops no)
	)
	(paper "A4")
	(title_block
		(title "timecard-production-celestica-r4006 — R4006-B0001-02_R01.brd")
		(comment 1 "Time Appliance Project (Time Card) / footprints 511-516 of 1113")
	)
	(layers
		(0 "F.Cu" signal "TOP")
		(4 "In1.Cu" signal "L02_GND1")
		(6 "In2.Cu" signal "L03_SIG1")
		(8 "In3.Cu" signal "L04_GND2")
		(10 "In4.Cu" signal "L05_VCC1")
		(12 "In5.Cu" signal "L06_VCC2")
		(14 "In6.Cu" signal "L07_GND3")
		(16 "In7.Cu" signal "L08_SIG2")
		(18 "In8.Cu" signal "L09_GND4")
		(2 "B.Cu" signal "BOTTOM")
		(9 "F.Adhes" user "F.Adhesive")
		(11 "B.Adhes" user "B.Adhesive")
		(13 "F.Paste" user "Package Geometry/Pastemask Top")
		(15 "B.Paste" user "Package Geometry/Pastemask Bottom")
		(5 "F.SilkS" user "Ref Des/Silkscreen Top")
		(7 "B.SilkS" user "Ref Des/Silkscreen Bottom")
		(1 "F.Mask" user "Board Geometry/Soldermask Top")
		(3 "B.Mask" user "Board Geometry/Soldermask Bottom")
		(17 "Dwgs.User" user "User.Drawings")
		(19 "Cmts.User" user "User.Comments")
		(21 "Eco1.User" user "User.Eco1")
		(23 "Eco2.User" user "User.Eco2")
		(25 "Edge.Cuts" user "Board Geometry/Outline")
		(27 "Margin" user)
		(31 "F.CrtYd" user "Package Geometry/Place Bound Top")
		(29 "B.CrtYd" user "Package Geometry/Place Bound Bottom")
		(35 "F.Fab" user "Ref Des/Assembly Top")
		(33 "B.Fab" user "Ref Des/Assembly Bottom")
	)
	(footprint ""
		(layer "F.Cu")
		(at 105.3846 -58.3692)
		(property "Reference" "TP183"
			(at 3.74015 2.159 90)
			(unlocked yes)
			(layer "F.SilkS")
			(effects
				(font
					(size 0.635 0.4064)
					(thickness 0.1524)
				)
				(justify left)
			)
		)
		(property "Value" ""
			(at 0 0 0)
			(layer "F.Fab")
			(effects
				(font
					(size 1.27 1.27)
				)
			)
		)
		(property "Device Type" "TP_PIONT-TP010CT020B030_PTH-TPA"
			(at -1.341882 0.996696 0)
			(unlocked yes)
			(layer "F.Fab")
			(hide yes)
			(effects
				(font
					(size 0.7874 0.5842)
					(thickness 0.1524)
				)
				(justify left)
			)
		)
		(duplicate_pad_numbers_are_jumpers no)
		(fp_poly
			(pts
				(arc
					(start 0.889 0)
					(mid -0.889 0)
					(end 0.889 0)
				)
			)
			(stroke
				(width 0)
				(type default)
			)
			(fill no)
			(layer "B.CrtYd")
		)
		(fp_poly
			(pts
				(arc
					(start 0.889 0)
					(mid -0.889 0)
					(end 0.889 0)
				)
			)
			(stroke
				(width 0)
				(type default)
			)
			(fill no)
			(layer "F.CrtYd")
		)
		(pad "1" thru_hole circle
			(at 0 0)
			(size 0.508 0.508)
			(drill 0.254)
			(layers "*.Cu" "*.Mask")
			(remove_unused_layers no)
			(net "IO_L22P_16")
			(clearance 0.1016)
			(padstack
				(mode front_inner_back)
				(layer "Inner"
					(shape circle)
					(size 0.508 0.508)
					(clearance 0.1016)
				)
				(layer "B.Cu"
					(shape circle)
					(size 0.762 0.762)
					(clearance -0.0254)
				)
			)
		)
	)
	(footprint ""
		(layer "F.Cu")
		(at 50.673 -131.826)
		(property "Reference" "SP61"
			(at 0 0 0)
			(layer "F.SilkS")
			(hide yes)
			(effects
				(font
					(size 1.27 1.27)
				)
			)
		)
		(property "Value" ""
			(at 0 0 0)
			(layer "F.Fab")
			(effects
				(font
					(size 1.27 1.27)
				)
			)
		)
		(duplicate_pad_numbers_are_jumpers no)
	)
	(footprint ""
		(layer "F.Cu")
		(at 111.887 -95.123)
		(property "Reference" "R453"
			(at 3.175 0.03937 0)
			(unlocked yes)
			(layer "F.SilkS")
			(effects
				(font
					(size 0.7874 0.5842)
					(thickness 0.1524)
				)
			)
		)
		(property "Value" "VAL*"
			(at 0.02032 2.13233 0)
			(unlocked yes)
			(layer "F.Fab")
			(hide yes)
			(effects
				(font
					(size 0.7874 0.5842)
					(thickness 0.1524)
				)
			)
		)
		(property "Tolerance" "TOL*"
			(at 0.044704 3.05435 0)
			(unlocked yes)
			(layer "Cmts.User")
			(hide yes)
			(effects
				(font
					(size 0.7874 0.5842)
					(thickness 0.1524)
				)
			)
		)
		(property "User Part Number" "PARTNUM*"
			(at 0.02032 4.024884 0)
			(unlocked yes)
			(layer "Cmts.User")
			(hide yes)
			(effects
				(font
					(size 0.7874 0.5842)
					(thickness 0.1524)
				)
			)
		)
		(property "Device Type" "RESISTOR-G155-11001-01,1KOHM,1%"
			(at 0.008382 1.210564 0)
			(unlocked yes)
			(layer "F.Fab")
			(hide yes)
			(effects
				(font
					(size 0.7874 0.5842)
					(thickness 0.1524)
				)
			)
		)
		(duplicate_pad_numbers_are_jumpers no)
		(fp_line
			(start -1.143 -0.5588)
			(end -1.143 0.5588)
			(stroke
				(width 0.1)
				(type default)
			)
			(layer "F.SilkS")
		)
		(fp_line
			(start -1.143 0.5588)
			(end 1.143 0.5588)
			(stroke
				(width 0.1)
				(type default)
			)
			(layer "F.SilkS")
		)
		(fp_line
			(start 1.143 -0.5588)
			(end -1.143 -0.5588)
			(stroke
				(width 0.1)
				(type default)
			)
			(layer "F.SilkS")
		)
		(fp_line
			(start 1.143 0.5588)
			(end 1.143 -0.5588)
			(stroke
				(width 0.1)
				(type default)
			)
			(layer "F.SilkS")
		)
		(fp_poly
			(pts
				(xy -1.143 0.5588) (xy 1.143 0.5588) (xy 1.143 -0.5588) (xy -1.143 -0.5588)
			)
			(stroke
				(width 0)
				(type default)
			)
			(fill no)
			(layer "F.CrtYd")
		)
		(fp_line
			(start -0.508 -0.3048)
			(end -0.508 0.3048)
			(stroke
				(width 0.1)
				(type default)
			)
			(layer "F.Fab")
		)
		(fp_line
			(start -0.508 0.3048)
			(end 0.508 0.3048)
			(stroke
				(width 0.1)
				(type default)
			)
			(layer "F.Fab")
		)
		(fp_line
			(start 0.508 -0.3048)
			(end -0.508 -0.3048)
			(stroke
				(width 0.1)
				(type default)
			)
			(layer "F.Fab")
		)
		(fp_line
			(start 0.508 0.3048)
			(end 0.508 -0.3048)
			(stroke
				(width 0.1)
				(type default)
			)
			(layer "F.Fab")
		)
		(pad "1" smd rect
			(at -0.5334 0)
			(size 0.7112 0.6096)
			(layers "F.Cu" "F.Mask" "F.Paste")
			(net "UNNAMED_524_POWERMOS3PNCHV1_I44")
		)
		(pad "2" smd rect
			(at 0.5334 0)
			(size 0.7112 0.6096)
			(layers "F.Cu" "F.Mask" "F.Paste")
			(net "SG")
		)
		(zone
			(layer "F.Cu")
			(hatch none 0.5)
			(connect_pads
				(clearance 0)
			)
			(min_thickness 0.25)
			(keepout
				(tracks not_allowed)
				(vias allowed)
				(pads allowed)
				(copperpour not_allowed)
				(footprints allowed)
			)
			(placement
				(enabled no)
				(sheetname "")
			)
			(fill
				(thermal_gap 0.5)
				(thermal_bridge_width 0.5)
				(island_removal_mode 0)
			)
			(polygon
				(pts
					(xy 111.8108 -94.8182) (xy 111.9632 -94.8182) (xy 111.9632 -95.4278) (xy 111.8108 -95.4278)
				)
			)
		)
		(zone
			(layer "F.Cu")
			(hatch none 0.5)
			(connect_pads
				(clearance 0)
			)
			(min_thickness 0.25)
			(keepout
				(tracks allowed)
				(vias not_allowed)
				(pads allowed)
				(copperpour not_allowed)
				(footprints allowed)
			)
			(placement
				(enabled no)
				(sheetname "")
			)
			(fill
				(thermal_gap 0.5)
				(thermal_bridge_width 0.5)
				(island_removal_mode 0)
			)
			(polygon
				(pts
					(xy 111.8108 -94.8182) (xy 111.9632 -94.8182) (xy 111.9632 -95.4278) (xy 111.8108 -95.4278)
				)
			)
		)
	)
	(footprint ""
		(layer "F.Cu")
		(at 80.772 -60.6806)
		(property "Reference" "R291"
			(at -10.287 -19.51863 0)
			(unlocked yes)
			(layer "F.SilkS")
			(effects
				(font
					(size 0.7874 0.5842)
					(thickness 0.1524)
				)
			)
		)
		(property "Value" "VAL*"
			(at 0.02032 2.13233 0)
			(unlocked yes)
			(layer "F.Fab")
			(hide yes)
			(effects
				(font
					(size 0.7874 0.5842)
					(thickness 0.1524)
				)
			)
		)
		(property "Tolerance" "TOL*"
			(at 0.044704 3.05435 0)
			(unlocked yes)
			(layer "Cmts.User")
			(hide yes)
			(effects
				(font
					(size 0.7874 0.5842)
					(thickness 0.1524)
				)
			)
		)
		(property "User Part Number" "PARTNUM*"
			(at 0.02032 4.024884 0)
			(unlocked yes)
			(layer "Cmts.User")
			(hide yes)
			(effects
				(font
					(size 0.7874 0.5842)
					(thickness 0.1524)
				)
			)
		)
		(property "Device Type" "RESISTOR-G155-14701-01,4.7KOHMA"
			(at 0.008382 1.210564 0)
			(unlocked yes)
			(layer "F.Fab")
			(hide yes)
			(effects
				(font
					(size 0.7874 0.5842)
					(thickness 0.1524)
				)
			)
		)
		(duplicate_pad_numbers_are_jumpers no)
		(fp_line
			(start -1.143 -0.5588)
			(end -1.143 0.5588)
			(stroke
				(width 0.1)
				(type default)
			)
			(layer "F.SilkS")
		)
		(fp_line
			(start -1.143 0.5588)
			(end 1.143 0.5588)
			(stroke
				(width 0.1)
				(type default)
			)
			(layer "F.SilkS")
		)
		(fp_line
			(start 1.143 -0.5588)
			(end -1.143 -0.5588)
			(stroke
				(width 0.1)
				(type default)
			)
			(layer "F.SilkS")
		)
		(fp_line
			(start 1.143 0.5588)
			(end 1.143 -0.5588)
			(stroke
				(width 0.1)
				(type default)
			)
			(layer "F.SilkS")
		)
		(fp_rect
			(start -1.143 0.5588)
			(end 1.143 -0.5588)
			(stroke
				(width 0)
				(type default)
			)
			(fill no)
			(layer "F.CrtYd")
		)
		(fp_line
			(start -0.508 -0.3048)
			(end -0.508 0.3048)
			(stroke
				(width 0.1)
				(type default)
			)
			(layer "F.Fab")
		)
		(fp_line
			(start -0.508 0.3048)
			(end 0.508 0.3048)
			(stroke
				(width 0.1)
				(type default)
			)
			(layer "F.Fab")
		)
		(fp_line
			(start 0.508 -0.3048)
			(end -0.508 -0.3048)
			(stroke
				(width 0.1)
				(type default)
			)
			(layer "F.Fab")
		)
		(fp_line
			(start 0.508 0.3048)
			(end 0.508 -0.3048)
			(stroke
				(width 0.1)
				(type default)
			)
			(layer "F.Fab")
		)
		(pad "1" smd rect
			(at -0.5334 0)
			(size 0.7112 0.6096)
			(layers "F.Cu" "F.Mask" "F.Paste")
			(net "XP3R3V_FPGA")
		)
		(pad "2" smd rect
			(at 0.5334 0)
			(size 0.7112 0.6096)
			(layers "F.Cu" "F.Mask" "F.Paste")
			(net "R_BNO080_RST_N")
		)
		(zone
			(layer "F.Cu")
			(hatch none 0.5)
			(connect_pads
				(clearance 0)
			)
			(min_thickness 0.25)
			(keepout
				(tracks allowed)
				(vias not_allowed)
				(pads allowed)
				(copperpour not_allowed)
				(footprints allowed)
			)
			(placement
				(enabled no)
				(sheetname "")
			)
			(fill
				(thermal_gap 0.5)
				(thermal_bridge_width 0.5)
				(island_removal_mode 0)
			)
			(polygon
				(pts
					(xy 80.6958 -60.3758) (xy 80.8482 -60.3758) (xy 80.8482 -60.9854) (xy 80.6958 -60.9854)
				)
			)
		)
	)
	(footprint ""
		(layer "F.Cu")
		(at 150.749 -24.511)
		(property "Reference" "R423"
			(at 0.127 2.45237 0)
			(unlocked yes)
			(layer "F.SilkS")
			(effects
				(font
					(size 0.7874 0.5842)
					(thickness 0.1524)
				)
			)
		)
		(property "Value" "VAL*"
			(at 0.02032 2.13233 0)
			(unlocked yes)
			(layer "F.Fab")
			(hide yes)
			(effects
				(font
					(size 0.7874 0.5842)
					(thickness 0.1524)
				)
			)
		)
		(property "Tolerance" "TOL*"
			(at 0.044704 3.05435 0)
			(unlocked yes)
			(layer "Cmts.User")
			(hide yes)
			(effects
				(font
					(size 0.7874 0.5842)
					(thickness 0.1524)
				)
			)
		)
		(property "User Part Number" "PARTNUM*"
			(at 0.02032 4.024884 0)
			(unlocked yes)
			(layer "Cmts.User")
			(hide yes)
			(effects
				(font
					(size 0.7874 0.5842)
					(thickness 0.1524)
				)
			)
		)
		(property "Device Type" "RESISTOR-G155-14701-01,4.7KOHMA"
			(at 0.008382 1.210564 0)
			(unlocked yes)
			(layer "F.Fab")
			(hide yes)
			(effects
				(font
					(size 0.7874 0.5842)
					(thickness 0.1524)
				)
			)
		)
		(duplicate_pad_numbers_are_jumpers no)
		(fp_line
			(start -1.143 -0.5588)
			(end -1.143 0.5588)
			(stroke
				(width 0.1)
				(type default)
			)
			(layer "F.SilkS")
		)
		(fp_line
			(start -1.143 0.5588)
			(end 1.143 0.5588)
			(stroke
				(width 0.1)
				(type default)
			)
			(layer "F.SilkS")
		)
		(fp_line
			(start 1.143 -0.5588)
			(end -1.143 -0.5588)
			(stroke
				(width 0.1)
				(type default)
			)
			(layer "F.SilkS")
		)
		(fp_line
			(start 1.143 0.5588)
			(end 1.143 -0.5588)
			(stroke
				(width 0.1)
				(type default)
			)
			(layer "F.SilkS")
		)
		(fp_rect
			(start -1.143 0.5588)
			(end 1.143 -0.5588)
			(stroke
				(width 0)
				(type default)
			)
			(fill no)
			(layer "F.CrtYd")
		)
		(fp_line
			(start -0.508 -0.3048)
			(end -0.508 0.3048)
			(stroke
				(width 0.1)
				(type default)
			)
			(layer "F.Fab")
		)
		(fp_line
			(start -0.508 0.3048)
			(end 0.508 0.3048)
			(stroke
				(width 0.1)
				(type default)
			)
			(layer "F.Fab")
		)
		(fp_line
			(start 0.508 -0.3048)
			(end -0.508 -0.3048)
			(stroke
				(width 0.1)
				(type default)
			)
			(layer "F.Fab")
		)
		(fp_line
			(start 0.508 0.3048)
			(end 0.508 -0.3048)
			(stroke
				(width 0.1)
				(type default)
			)
			(layer "F.Fab")
		)
		(pad "1" smd rect
			(at -0.5334 0)
			(size 0.7112 0.6096)
			(layers "F.Cu" "F.Mask" "F.Paste")
			(net "XP3R3V_FPGA")
		)
		(pad "2" smd rect
			(at 0.5334 0)
			(size 0.7112 0.6096)
			(layers "F.Cu" "F.Mask" "F.Paste")
			(net "FPGA_IN_LM75B_INT3_N")
		)
		(zone
			(layer "F.Cu")
			(hatch none 0.5)
			(connect_pads
				(clearance 0)
			)
			(min_thickness 0.25)
			(keepout
				(tracks allowed)
				(vias not_allowed)
				(pads allowed)
				(copperpour not_allowed)
				(footprints allowed)
			)
			(placement
				(enabled no)
				(sheetname "")
			)
			(fill
				(thermal_gap 0.5)
				(thermal_bridge_width 0.5)
				(island_removal_mode 0)
			)
			(polygon
				(pts
					(xy 150.6728 -24.2062) (xy 150.8252 -24.2062) (xy 150.8252 -24.8158) (xy 150.6728 -24.8158)
				)
			)
		)
		(zone
			(layer "F.Cu")
			(hatch none 0.5)
			(connect_pads
				(clearance 0)
			)
			(min_thickness 0.25)
			(keepout
				(tracks not_allowed)
				(vias allowed)
				(pads allowed)
				(copperpour not_allowed)
				(footprints allowed)
			)
			(placement
				(enabled no)
				(sheetname "")
			)
			(fill
				(thermal_gap 0.5)
				(thermal_bridge_width 0.5)
				(island_removal_mode 0)
			)
			(polygon
				(pts
					(xy 150.6728 -24.2062) (xy 150.8252 -24.2062) (xy 150.8252 -24.8158) (xy 150.6728 -24.8158)
				)
			)
		)
	)
	(footprint ""
		(layer "F.Cu")
		(at 111.125 -104.521 180)
		(property "Reference" "R366"
			(at -3.175 3.00863 0)
			(unlocked yes)
			(layer "F.SilkS")
			(effects
				(font
					(size 0.7874 0.5842)
					(thickness 0.1524)
				)
			)
		)
		(property "Value" "VAL*"
			(at 0.02032 2.13233 180)
			(unlocked yes)
			(layer "F.Fab")
			(hide yes)
			(effects
				(font
					(size 0.7874 0.5842)
					(thickness 0.1524)
				)
			)
		)
		(property "Tolerance" "TOL*"
			(at 0.044704 3.05435 180)
			(unlocked yes)
			(layer "Cmts.User")
			(hide yes)
			(effects
				(font
					(size 0.7874 0.5842)
					(thickness 0.1524)
				)
			)
		)
		(property "User Part Number" "PARTNUM*"
			(at 0.02032 4.024884 180)
			(unlocked yes)
			(layer "Cmts.User")
			(hide yes)
			(effects
				(font
					(size 0.7874 0.5842)
					(thickness 0.1524)
				)
			)
		)
		(property "Device Type" "RESISTOR-G155-133R0-01,33OHM,1%"
			(at 0.008382 1.210564 180)
			(unlocked yes)
			(layer "F.Fab")
			(hide yes)
			(effects
				(font
					(size 0.7874 0.5842)
					(thickness 0.1524)
				)
			)
		)
		(duplicate_pad_numbers_are_jumpers no)
		(fp_line
			(start 1.143 0.5588)
			(end 1.143 -0.5588)
			(stroke
				(width 0.1)
				(type default)
			)
			(layer "F.SilkS")
		)
		(fp_line
			(start 1.143 -0.5588)
			(end -1.143 -0.5588)
			(stroke
				(width 0.1)
				(type default)
			)
			(layer "F.SilkS")
		)
		(fp_line
			(start -1.143 0.5588)
			(end 1.143 0.5588)
			(stroke
				(width 0.1)
				(type default)
			)
			(layer "F.SilkS")
		)
		(fp_line
			(start -1.143 -0.5588)
			(end -1.143 0.5588)
			(stroke
				(width 0.1)
				(type default)
			)
			(layer "F.SilkS")
		)
		(fp_poly
			(pts
				(xy -1.143 0.5588) (xy 1.143 0.5588) (xy 1.143 -0.5588) (xy -1.143 -0.5588)
			)
			(stroke
				(width 0)
				(type default)
			)
			(fill no)
			(layer "F.CrtYd")
		)
		(fp_line
			(start 0.508 0.3048)
			(end 0.508 -0.3048)
			(stroke
				(width 0.1)
				(type default)
			)
			(layer "F.Fab")
		)
		(fp_line
			(start 0.508 -0.3048)
			(end -0.508 -0.3048)
			(stroke
				(width 0.1)
				(type default)
			)
			(layer "F.Fab")
		)
		(fp_line
			(start -0.508 0.3048)
			(end 0.508 0.3048)
			(stroke
				(width 0.1)
				(type default)
			)
			(layer "F.Fab")
		)
		(fp_line
			(start -0.508 -0.3048)
			(end -0.508 0.3048)
			(stroke
				(width 0.1)
				(type default)
			)
			(layer "F.Fab")
		)
		(pad "1" smd rect
			(at -0.5334 0 180)
			(size 0.7112 0.6096)
			(layers "F.Cu" "F.Mask" "F.Paste")
			(net "RGB_LED_I2C_SCL")
		)
		(pad "2" smd rect
			(at 0.5334 0 180)
			(size 0.7112 0.6096)
			(layers "F.Cu" "F.Mask" "F.Paste")
			(net "R_RGB_LED_I2C_SCL")
		)
		(zone
			(layer "F.Cu")
			(hatch none 0.5)
			(connect_pads
				(clearance 0)
			)
			(min_thickness 0.25)
			(keepout
				(tracks allowed)
				(vias not_allowed)
				(pads allowed)
				(copperpour not_allowed)
				(footprints allowed)
			)
			(placement
				(enabled no)
				(sheetname "")
			)
			(fill
				(thermal_gap 0.5)
				(thermal_bridge_width 0.5)
				(island_removal_mode 0)
			)
			(polygon
				(pts
					(xy 111.2012 -104.8258) (xy 111.0488 -104.8258) (xy 111.0488 -104.2162) (xy 111.2012 -104.2162)
				)
			)
		)
		(zone
			(layer "F.Cu")
			(hatch none 0.5)
			(connect_pads
				(clearance 0)
			)
			(min_thickness 0.25)
			(keepout
				(tracks not_allowed)
				(vias allowed)
				(pads allowed)
				(copperpour not_allowed)
				(footprints allowed)
			)
			(placement
				(enabled no)
				(sheetname "")
			)
			(fill
				(thermal_gap 0.5)
				(thermal_bridge_width 0.5)
				(island_removal_mode 0)
			)
			(polygon
				(pts
					(xy 111.2012 -104.8258) (xy 111.0488 -104.8258) (xy 111.0488 -104.2162) (xy 111.2012 -104.2162)
				)
			)
		)
	)
)
